(kicad_pcb
	(version 20240108)
	(generator "pcbnew")
	(generator_version "8.0")
	(general
		(thickness 1.6)
		(legacy_teardrops no)
	)
	(paper "A4")
	(title_block
		(title "Jetson Orin Baseboard OCuLink Expansion")
		(date "2025-03-18")
		(rev "1.1.0")
		(company "Antmicro Ltd")
		(comment 1 "www.antmicro.com")
		(comment 9 "footprints 95-98 of 119")
	)
	(layers
		(0 "F.Cu" signal)
		(1 "In1.Cu" signal)
		(2 "In2.Cu" signal)
		(31 "B.Cu" signal)
		(32 "B.Adhes" user "B.Adhesive")
		(33 "F.Adhes" user "F.Adhesive")
		(34 "B.Paste" user)
		(35 "F.Paste" user)
		(36 "B.SilkS" user "B.Silkscreen")
		(37 "F.SilkS" user "F.Silkscreen")
		(38 "B.Mask" user)
		(39 "F.Mask" user)
		(40 "Dwgs.User" user "User.Drawings")
		(41 "Cmts.User" user "User.Comments")
		(42 "Eco1.User" user "User.Eco1")
		(43 "Eco2.User" user "User.Eco2")
		(44 "Edge.Cuts" user)
		(45 "Margin" user)
		(46 "B.CrtYd" user "B.Courtyard")
		(47 "F.CrtYd" user "F.Courtyard")
		(48 "B.Fab" user)
		(49 "F.Fab" user)
	)
	(footprint "antmicro-footprints:R_0402_1005Metric"
		(layer "B.Cu")
		(at 118.324 116.653751 180)
		(descr "Resistor SMD 0402")
		(tags "resistor SMD 0402")
		(property "Reference" "R8"
			(at -2.589333 -0.47725 0)
			(layer "B.SilkS")
			(effects
				(font
					(size 0.7 0.7)
					(thickness 0.15)
				)
				(justify left bottom mirror)
			)
		)
		(property "Value" "R_1k_0402"
			(at -1.011843 -1.772047 0)
			(layer "B.Fab")
			(effects
				(font
					(size 0.7 0.7)
					(thickness 0.15)
				)
				(justify left bottom mirror)
			)
		)
		(property "Footprint" "antmicro-footprints:R_0402_1005Metric"
			(at 0 0 0)
			(layer "B.Fab")
			(hide yes)
			(effects
				(font
					(size 1.27 1.27)
					(thickness 0.15)
				)
				(justify mirror)
			)
		)
		(property "Datasheet" "https://www.bourns.com/docs/product-datasheets/cr.pdf"
			(at 0 0 0)
			(layer "B.Fab")
			(hide yes)
			(effects
				(font
					(size 1.27 1.27)
					(thickness 0.15)
				)
				(justify mirror)
			)
		)
		(property "Description" "SMD Chip Resistor, 1 kohm, ± 1%, 63 mW, 0402 [1005 Metric], Thick Film, General Purpose"
			(at 0 0 0)
			(layer "B.Fab")
			(hide yes)
			(effects
				(font
					(size 1.27 1.27)
					(thickness 0.15)
				)
				(justify mirror)
			)
		)
		(property "MPN" "CR0402-FX-1001GLF"
			(at 0 0 0)
			(unlocked yes)
			(layer "B.Fab")
			(hide yes)
			(effects
				(font
					(size 1 1)
					(thickness 0.15)
				)
				(justify mirror)
			)
		)
		(property "Manufacturer" "Bourns"
			(at 0 0 0)
			(unlocked yes)
			(layer "B.Fab")
			(hide yes)
			(effects
				(font
					(size 1 1)
					(thickness 0.15)
				)
				(justify mirror)
			)
		)
		(property "License" "Apache-2.0"
			(at 0 0 0)
			(unlocked yes)
			(layer "B.Fab")
			(hide yes)
			(effects
				(font
					(size 1 1)
					(thickness 0.15)
				)
				(justify mirror)
			)
		)
		(property "Author" "Antmicro"
			(at 0 0 0)
			(unlocked yes)
			(layer "B.Fab")
			(hide yes)
			(effects
				(font
					(size 1 1)
					(thickness 0.15)
				)
				(justify mirror)
			)
		)
		(property "Val" "1k"
			(at 0 0 0)
			(unlocked yes)
			(layer "B.Fab")
			(hide yes)
			(effects
				(font
					(size 1 1)
					(thickness 0.15)
				)
				(justify mirror)
			)
		)
		(property "Tolerance" "1%"
			(at 0 0 0)
			(unlocked yes)
			(layer "B.Fab")
			(hide yes)
			(effects
				(font
					(size 1 1)
					(thickness 0.15)
				)
				(justify mirror)
			)
		)
		(property "Public" "False"
			(at 0 0 0)
			(unlocked yes)
			(layer "B.Fab")
			(hide yes)
			(effects
				(font
					(size 1 1)
					(thickness 0.15)
				)
				(justify mirror)
			)
		)
		(sheetname "Root")
		(sheetfile "jetson-orin-baseboard-oculink-expansion.kicad_sch")
		(attr smd)
		(fp_rect
			(start -0.925 0.47)
			(end 0.925 -0.47)
			(stroke
				(width 0.05)
				(type default)
			)
			(fill none)
			(layer "B.CrtYd")
		)
		(fp_rect
			(start -0.5 0.25)
			(end 0.5 -0.25)
			(stroke
				(width 0.15)
				(type solid)
			)
			(fill none)
			(layer "B.Fab")
		)
		(fp_text user "License: Apache-2.0"
			(at -0.95 -5.169 0)
			(layer "B.Fab")
			(hide yes)
			(effects
				(font
					(size 0.7 0.7)
					(thickness 0.15)
				)
				(justify left bottom mirror)
			)
		)
		(fp_text user "Author: Antmicro"
			(at -0.95 -4.169 0)
			(layer "B.Fab")
			(hide yes)
			(effects
				(font
					(size 0.7 0.7)
					(thickness 0.15)
				)
				(justify left bottom mirror)
			)
		)
		(fp_text user "${REFERENCE}"
			(at -0.95 -3.168 0)
			(layer "B.Fab")
			(hide yes)
			(effects
				(font
					(size 0.7 0.7)
					(thickness 0.15)
				)
				(justify left bottom mirror)
			)
		)
		(pad "1" smd roundrect
			(at -0.48 0 180)
			(size 0.59 0.64)
			(layers "B.Cu" "B.Paste" "B.Mask")
			(roundrect_rratio 0.25)
			(net 23 "+3V3")
			(pintype "passive")
		)
		(pad "2" smd roundrect
			(at 0.48 0 180)
			(size 0.59 0.64)
			(layers "B.Cu" "B.Paste" "B.Mask")
			(roundrect_rratio 0.25)
			(net 91 "/RX_EQ2")
			(pintype "passive")
		)
	)
	(footprint "antmicro-footprints:C_0402_1005Metric"
		(layer "B.Cu")
		(at 123.505 116.687251 -90)
		(descr "Capacitor SMD 0402")
		(tags "capacitor SMD 0402")
		(property "Reference" "C24"
			(at 1.782749 -0.445 90)
			(layer "B.SilkS")
			(effects
				(font
					(size 0.7 0.7)
					(thickness 0.15)
				)
				(justify left bottom mirror)
			)
		)
		(property "Value" "C_100n_0402"
			(at -1.022927 -2.155213 90)
			(layer "B.Fab")
			(effects
				(font
					(size 0.7 0.7)
					(thickness 0.15)
				)
				(justify left bottom mirror)
			)
		)
		(property "Footprint" "antmicro-footprints:C_0402_1005Metric"
			(at 0 0 90)
			(layer "B.Fab")
			(hide yes)
			(effects
				(font
					(size 1.27 1.27)
					(thickness 0.15)
				)
				(justify mirror)
			)
		)
		(property "Datasheet" "https://www.murata.com/products/productdetail?partno=GRM155R61H104KE14%23"
			(at 0 0 90)
			(layer "B.Fab")
			(hide yes)
			(effects
				(font
					(size 1.27 1.27)
					(thickness 0.15)
				)
				(justify mirror)
			)
		)
		(property "Description" "SMD Multilayer Ceramic Capacitor, 0.1 µF, 50 V, 0402 [1005 Metric], ± 10%, X5R, GRM Series"
			(at 0 0 90)
			(layer "B.Fab")
			(hide yes)
			(effects
				(font
					(size 1.27 1.27)
					(thickness 0.15)
				)
				(justify mirror)
			)
		)
		(property "MPN" "GRM155R61H104KE14D"
			(at 0 0 90)
			(unlocked yes)
			(layer "B.Fab")
			(hide yes)
			(effects
				(font
					(size 1 1)
					(thickness 0.15)
				)
				(justify mirror)
			)
		)
		(property "Manufacturer" "Murata"
			(at 0 0 90)
			(unlocked yes)
			(layer "B.Fab")
			(hide yes)
			(effects
				(font
					(size 1 1)
					(thickness 0.15)
				)
				(justify mirror)
			)
		)
		(property "License" "Apache-2.0"
			(at 0 0 90)
			(unlocked yes)
			(layer "B.Fab")
			(hide yes)
			(effects
				(font
					(size 1 1)
					(thickness 0.15)
				)
				(justify mirror)
			)
		)
		(property "Author" "Antmicro"
			(at 0 0 90)
			(unlocked yes)
			(layer "B.Fab")
			(hide yes)
			(effects
				(font
					(size 1 1)
					(thickness 0.15)
				)
				(justify mirror)
			)
		)
		(property "Val" "100n"
			(at 0 0 90)
			(unlocked yes)
			(layer "B.Fab")
			(hide yes)
			(effects
				(font
					(size 1 1)
					(thickness 0.15)
				)
				(justify mirror)
			)
		)
		(property "Voltage" "50V"
			(at 0 0 90)
			(unlocked yes)
			(layer "B.Fab")
			(hide yes)
			(effects
				(font
					(size 1 1)
					(thickness 0.15)
				)
				(justify mirror)
			)
		)
		(property "Dielectric" "X5R"
			(at 0 0 90)
			(unlocked yes)
			(layer "B.Fab")
			(hide yes)
			(effects
				(font
					(size 1 1)
					(thickness 0.15)
				)
				(justify mirror)
			)
		)
		(property "Public" "False"
			(at 0 0 90)
			(unlocked yes)
			(layer "B.Fab")
			(hide yes)
			(effects
				(font
					(size 1 1)
					(thickness 0.15)
				)
				(justify mirror)
			)
		)
		(sheetname "Root")
		(sheetfile "jetson-orin-baseboard-oculink-expansion.kicad_sch")
		(attr smd)
		(fp_rect
			(start -0.925 0.47)
			(end 0.925 -0.47)
			(stroke
				(width 0.05)
				(type default)
			)
			(fill none)
			(layer "B.CrtYd")
		)
		(fp_line
			(start -0.494 0.25)
			(end -0.494 -0.248)
			(stroke
				(width 0.15)
				(type solid)
			)
			(layer "B.Fab")
		)
		(fp_line
			(start 0.504 0.25)
			(end -0.494 0.25)
			(stroke
				(width 0.15)
				(type solid)
			)
			(layer "B.Fab")
		)
		(fp_line
			(start -0.494 -0.248)
			(end 0.504 -0.248)
			(stroke
				(width 0.15)
				(type solid)
			)
			(layer "B.Fab")
		)
		(fp_line
			(start 0.504 -0.248)
			(end 0.504 0.25)
			(stroke
				(width 0.15)
				(type solid)
			)
			(layer "B.Fab")
		)
		(fp_text user "Author: Antmicro"
			(at -0.939 -3.399 90)
			(layer "B.Fab")
			(hide yes)
			(effects
				(font
					(size 0.7 0.7)
					(thickness 0.15)
				)
				(justify left bottom mirror)
			)
		)
		(fp_text user "${REFERENCE}"
			(at -0.939 -4.599 90)
			(layer "B.Fab")
			(hide yes)
			(effects
				(font
					(size 0.7 0.7)
					(thickness 0.15)
				)
				(justify left bottom mirror)
			)
		)
		(fp_text user "License: Apache-2.0"
			(at -0.939 -5.799 90)
			(layer "B.Fab")
			(hide yes)
			(effects
				(font
					(size 0.7 0.7)
					(thickness 0.15)
				)
				(justify left bottom mirror)
			)
		)
		(pad "1" smd roundrect
			(at -0.48 0 270)
			(size 0.59 0.64)
			(layers "B.Cu" "B.Paste" "B.Mask")
			(roundrect_rratio 0.25)
			(net 51 "GND")
			(pintype "passive")
		)
		(pad "2" smd roundrect
			(at 0.48 0 270)
			(size 0.59 0.64)
			(layers "B.Cu" "B.Paste" "B.Mask")
			(roundrect_rratio 0.25)
			(net 23 "+3V3")
			(pintype "passive")
		)
	)
	(footprint "antmicro-footprints:R_0402_1005Metric"
		(layer "B.Cu")
		(at 129.72 113.79)
		(descr "Resistor SMD 0402")
		(tags "resistor SMD 0402")
		(property "Reference" "R31"
			(at 0.65 -0.34 0)
			(layer "B.SilkS")
			(effects
				(font
					(size 0.7 0.7)
					(thickness 0.15)
				)
				(justify right top mirror)
			)
		)
		(property "Value" "R_10k_0402"
			(at -1.011843 -1.772047 0)
			(layer "B.Fab")
			(effects
				(font
					(size 0.7 0.7)
					(thickness 0.15)
				)
				(justify right top mirror)
			)
		)
		(property "Footprint" "antmicro-footprints:R_0402_1005Metric"
			(at 0 0 0)
			(layer "B.Fab")
			(hide yes)
			(effects
				(font
					(size 1.27 1.27)
					(thickness 0.15)
				)
				(justify mirror)
			)
		)
		(property "Datasheet" "https://www.bourns.com/docs/product-datasheets/cr.pdf"
			(at 0 0 0)
			(layer "B.Fab")
			(hide yes)
			(effects
				(font
					(size 1.27 1.27)
					(thickness 0.15)
				)
				(justify mirror)
			)
		)
		(property "Description" "SMD Chip Resistor, 10 kohm, ± 1%, 62.5 mW, 0402 [1005 Metric], Thick Film, General Purpose"
			(at 0 0 0)
			(layer "B.Fab")
			(hide yes)
			(effects
				(font
					(size 1.27 1.27)
					(thickness 0.15)
				)
				(justify mirror)
			)
		)
		(property "MPN" "CR0402-FX-1002GLF"
			(at 0 0 180)
			(unlocked yes)
			(layer "B.Fab")
			(hide yes)
			(effects
				(font
					(size 1 1)
					(thickness 0.15)
				)
				(justify mirror)
			)
		)
		(property "Manufacturer" "Bourns"
			(at 0 0 180)
			(unlocked yes)
			(layer "B.Fab")
			(hide yes)
			(effects
				(font
					(size 1 1)
					(thickness 0.15)
				)
				(justify mirror)
			)
		)
		(property "License" "Apache-2.0"
			(at 0 0 180)
			(unlocked yes)
			(layer "B.Fab")
			(hide yes)
			(effects
				(font
					(size 1 1)
					(thickness 0.15)
				)
				(justify mirror)
			)
		)
		(property "Author" "Antmicro"
			(at 0 0 180)
			(unlocked yes)
			(layer "B.Fab")
			(hide yes)
			(effects
				(font
					(size 1 1)
					(thickness 0.15)
				)
				(justify mirror)
			)
		)
		(property "Val" "10k"
			(at 0 0 180)
			(unlocked yes)
			(layer "B.Fab")
			(hide yes)
			(effects
				(font
					(size 1 1)
					(thickness 0.15)
				)
				(justify mirror)
			)
		)
		(property "Tolerance" "1%"
			(at 0 0 180)
			(unlocked yes)
			(layer "B.Fab")
			(hide yes)
			(effects
				(font
					(size 1 1)
					(thickness 0.15)
				)
				(justify mirror)
			)
		)
		(sheetname "Root")
		(sheetfile "jetson-orin-baseboard-oculink-expansion.kicad_sch")
		(attr smd)
		(fp_rect
			(start -0.925 0.47)
			(end 0.925 -0.47)
			(stroke
				(width 0.05)
				(type default)
			)
			(fill none)
			(layer "B.CrtYd")
		)
		(fp_rect
			(start -0.5 0.25)
			(end 0.5 -0.25)
			(stroke
				(width 0.15)
				(type solid)
			)
			(fill none)
			(layer "B.Fab")
		)
		(fp_text user "License: Apache-2.0"
			(at -0.95 -5.169 0)
			(layer "B.Fab")
			(hide yes)
			(effects
				(font
					(size 0.7 0.7)
					(thickness 0.15)
				)
				(justify right top mirror)
			)
		)
		(fp_text user "${REFERENCE}"
			(at -0.95 -3.168 0)
			(layer "B.Fab")
			(hide yes)
			(effects
				(font
					(size 0.7 0.7)
					(thickness 0.15)
				)
				(justify right top mirror)
			)
		)
		(fp_text user "Author: Antmicro"
			(at -0.95 -4.169 0)
			(layer "B.Fab")
			(hide yes)
			(effects
				(font
					(size 0.7 0.7)
					(thickness 0.15)
				)
				(justify right top mirror)
			)
		)
		(pad "1" smd roundrect
			(at -0.48 0)
			(size 0.59 0.64)
			(layers "B.Cu" "B.Paste" "B.Mask")
			(roundrect_rratio 0.25)
			(net 51 "GND")
			(pintype "passive")
		)
		(pad "2" smd roundrect
			(at 0.48 0)
			(size 0.59 0.64)
			(layers "B.Cu" "B.Paste" "B.Mask")
			(roundrect_rratio 0.25)
			(net 103 "Net-(U2-EN_{I2C})")
			(pintype "passive")
		)
	)
	(footprint "antmicro-footprints:R_0402_1005Metric"
		(layer "B.Cu")
		(at 116.55 129.22 180)
		(descr "Resistor SMD 0402")
		(tags "resistor SMD 0402")
		(property "Reference" "R38"
			(at 0.79 -0.22 0)
			(layer "B.SilkS")
			(effects
				(font
					(size 0.7 0.7)
					(thickness 0.15)
				)
				(justify left bottom mirror)
			)
		)
		(property "Value" "R_0R_0402"
			(at -1.011843 -1.772047 0)
			(layer "B.Fab")
			(effects
				(font
					(size 0.7 0.7)
					(thickness 0.15)
				)
				(justify left bottom mirror)
			)
		)
		(property "Footprint" "antmicro-footprints:R_0402_1005Metric"
			(at 0 0 0)
			(layer "B.Fab")
			(hide yes)
			(effects
				(font
					(size 1.27 1.27)
					(thickness 0.15)
				)
				(justify mirror)
			)
		)
		(property "Datasheet" "https://industrial.panasonic.com/cdbs/www-data/pdf/RDA0000/AOA0000C301.pdf"
			(at 0 0 0)
			(layer "B.Fab")
			(hide yes)
			(effects
				(font
					(size 1.27 1.27)
					(thickness 0.15)
				)
				(justify mirror)
			)
		)
		(property "Description" "SMD Chip Resistor, Jumper, 0 ohm, 100 mW, 0402 [1005 Metric], Thick Film, General Purpose"
			(at 0 0 0)
			(layer "B.Fab")
			(hide yes)
			(effects
				(font
					(size 1.27 1.27)
					(thickness 0.15)
				)
				(justify mirror)
			)
		)
		(property "MPN" "ERJ2GE0R00X"
			(at 0 0 0)
			(unlocked yes)
			(layer "B.Fab")
			(hide yes)
			(effects
				(font
					(size 1 1)
					(thickness 0.15)
				)
				(justify mirror)
			)
		)
		(property "Manufacturer" "Panasonic"
			(at 0 0 0)
			(unlocked yes)
			(layer "B.Fab")
			(hide yes)
			(effects
				(font
					(size 1 1)
					(thickness 0.15)
				)
				(justify mirror)
			)
		)
		(property "License" "Apache-2.0"
			(at 0 0 0)
			(unlocked yes)
			(layer "B.Fab")
			(hide yes)
			(effects
				(font
					(size 1 1)
					(thickness 0.15)
				)
				(justify mirror)
			)
		)
		(property "Author" "Antmicro"
			(at 0 0 0)
			(unlocked yes)
			(layer "B.Fab")
			(hide yes)
			(effects
				(font
					(size 1 1)
					(thickness 0.15)
				)
				(justify mirror)
			)
		)
		(property "Val" "0R"
			(at 0 0 0)
			(unlocked yes)
			(layer "B.Fab")
			(hide yes)
			(effects
				(font
					(size 1 1)
					(thickness 0.15)
				)
				(justify mirror)
			)
		)
		(property "Tolerance" ""
			(at 0 0 0)
			(unlocked yes)
			(layer "B.Fab")
			(hide yes)
			(effects
				(font
					(size 1 1)
					(thickness 0.15)
				)
				(justify mirror)
			)
		)
		(property "Current" "1A"
			(at 0 0 0)
			(unlocked yes)
			(layer "B.Fab")
			(hide yes)
			(effects
				(font
					(size 1 1)
					(thickness 0.15)
				)
				(justify mirror)
			)
		)
		(property "Public" "False"
			(at 0 0 0)
			(unlocked yes)
			(layer "B.Fab")
			(hide yes)
			(effects
				(font
					(size 1 1)
					(thickness 0.15)
				)
				(justify mirror)
			)
		)
		(sheetname "Root")
		(sheetfile "jetson-orin-baseboard-oculink-expansion.kicad_sch")
		(attr smd dnp)
		(fp_rect
			(start -0.925 0.47)
			(end 0.925 -0.47)
			(stroke
				(width 0.05)
				(type default)
			)
			(fill none)
			(layer "B.CrtYd")
		)
		(fp_rect
			(start -0.5 0.25)
			(end 0.5 -0.25)
			(stroke
				(width 0.15)
				(type solid)
			)
			(fill none)
			(layer "B.Fab")
		)
		(fp_text user "License: Apache-2.0"
			(at -0.95 -5.169 0)
			(layer "B.Fab")
			(hide yes)
			(effects
				(font
					(size 0.7 0.7)
					(thickness 0.15)
				)
				(justify left bottom mirror)
			)
		)
		(fp_text user "Author: Antmicro"
			(at -0.95 -4.169 0)
			(layer "B.Fab")
			(hide yes)
			(effects
				(font
					(size 0.7 0.7)
					(thickness 0.15)
				)
				(justify left bottom mirror)
			)
		)
		(fp_text user "${REFERENCE}"
			(at -0.95 -3.168 0)
			(layer "B.Fab")
			(hide yes)
			(effects
				(font
					(size 0.7 0.7)
					(thickness 0.15)
				)
				(justify left bottom mirror)
			)
		)
		(pad "1" smd roundrect
			(at -0.48 0 180)
			(size 0.59 0.64)
			(layers "B.Cu" "B.Paste" "B.Mask")
			(roundrect_rratio 0.25)
			(net 23 "+3V3")
			(pintype "passive")
		)
		(pad "2" smd roundrect
			(at 0.48 0 180)
			(size 0.59 0.64)
			(layers "B.Cu" "B.Paste" "B.Mask")
			(roundrect_rratio 0.25)
			(net 105 "Net-(U3-EN_{I2C})")
			(pintype "passive")
		)
	)
)
